(kicad_pcb
	(version 20260206)
	(generator "pcbnew")
	(generator_version "10.0")
	(general
		(thickness 1.6)
		(legacy_teardrops no)
	)
	(paper "A4")
	(title_block
		(title "01162023_DA0F0TEBIF0_F0T_Expander_BD_F_brd_V02_OCP.brd")
		(comment 1 "Grand Teton / footprints 8493-8501 of 9728")
	)
	(layers
		(0 "F.Cu" signal "TOP")
		(4 "In1.Cu" signal "GND")
		(6 "In2.Cu" signal "VCC")
		(8 "In3.Cu" signal "VCC1")
		(10 "In4.Cu" signal "GND1")
		(12 "In5.Cu" signal "IN1")
		(14 "In6.Cu" signal "GND2")
		(16 "In7.Cu" signal "IN2")
		(18 "In8.Cu" signal "GND3")
		(20 "In9.Cu" signal "IN3")
		(22 "In10.Cu" signal "GND4")
		(24 "In11.Cu" signal "IN4")
		(26 "In12.Cu" signal "GND5")
		(28 "In13.Cu" signal "IN5")
		(30 "In14.Cu" signal "GND6")
		(32 "In15.Cu" signal "IN6")
		(34 "In16.Cu" signal "GND7")
		(2 "B.Cu" signal "BOTTOM")
		(9 "F.Adhes" user "F.Adhesive")
		(11 "B.Adhes" user "B.Adhesive")
		(13 "F.Paste" user "Package Geometry/Pastemask Top")
		(15 "B.Paste" user "Package Geometry/Pastemask Bottom")
		(5 "F.SilkS" user "Ref Des/Silkscreen Top")
		(7 "B.SilkS" user "Ref Des/Silkscreen Bottom")
		(1 "F.Mask" user "Board Geometry/Soldermask Top")
		(3 "B.Mask" user "Board Geometry/Soldermask Bottom")
		(17 "Dwgs.User" user "User.Drawings")
		(19 "Cmts.User" user "User.Comments")
		(21 "Eco1.User" user "User.Eco1")
		(23 "Eco2.User" user "User.Eco2")
		(25 "Edge.Cuts" user "Board Geometry/Outline")
		(27 "Margin" user)
		(31 "F.CrtYd" user "Package Geometry/Place Bound Top")
		(29 "B.CrtYd" user "Package Geometry/Place Bound Bottom")
		(35 "F.Fab" user "Ref Des/Assembly Top")
		(33 "B.Fab" user "Ref Des/Assembly Bottom")
	)
	(footprint ""
		(layer "B.Cu")
		(at 348.328488 -303.141634 180)
		(property "Reference" "PR125"
			(at 0 0 0)
			(layer "B.SilkS")
			(hide yes)
			(effects
				(font
					(size 1.27 1.27)
				)
				(justify mirror)
			)
		)
		(property "Value" ""
			(at 0 0 0)
			(layer "B.Fab")
			(effects
				(font
					(size 1.27 1.27)
				)
				(justify mirror)
			)
		)
		(duplicate_pad_numbers_are_jumpers no)
		(fp_line
			(start 0.7874 0.4064)
			(end 0.7874 -0.4064)
			(stroke
				(width 0.1524)
				(type default)
			)
			(layer "B.SilkS")
		)
		(fp_line
			(start 0.7874 -0.4064)
			(end -0.7874 -0.4064)
			(stroke
				(width 0.1524)
				(type default)
			)
			(layer "B.SilkS")
		)
		(fp_line
			(start -0.7874 0.4064)
			(end 0.7874 0.4064)
			(stroke
				(width 0.1524)
				(type default)
			)
			(layer "B.SilkS")
		)
		(fp_line
			(start -0.7874 -0.4064)
			(end -0.7874 0.4064)
			(stroke
				(width 0.1524)
				(type default)
			)
			(layer "B.SilkS")
		)
		(fp_line
			(start 0.67945 0.3048)
			(end 0.67945 -0.305054)
			(stroke
				(width 0.1)
				(type default)
			)
			(layer "B.Fab")
		)
		(fp_line
			(start 0.67945 -0.305054)
			(end 0.12065 -0.305054)
			(stroke
				(width 0.1)
				(type default)
			)
			(layer "B.Fab")
		)
		(fp_line
			(start 0.12065 0.3048)
			(end 0.67945 0.3048)
			(stroke
				(width 0.1)
				(type default)
			)
			(layer "B.Fab")
		)
		(fp_line
			(start 0.12065 0.2794)
			(end 0.12065 0.3048)
			(stroke
				(width 0.1)
				(type default)
			)
			(layer "B.Fab")
		)
		(fp_line
			(start 0.12065 -0.2794)
			(end -0.12065 -0.2794)
			(stroke
				(width 0.1)
				(type default)
			)
			(layer "B.Fab")
		)
		(fp_line
			(start 0.12065 -0.305054)
			(end 0.12065 -0.2794)
			(stroke
				(width 0.1)
				(type default)
			)
			(layer "B.Fab")
		)
		(fp_line
			(start -0.120396 0.3048)
			(end -0.120396 0.2794)
			(stroke
				(width 0.1)
				(type default)
			)
			(layer "B.Fab")
		)
		(fp_line
			(start -0.120396 0.2794)
			(end 0.12065 0.2794)
			(stroke
				(width 0.1)
				(type default)
			)
			(layer "B.Fab")
		)
		(fp_line
			(start -0.12065 -0.2794)
			(end -0.12065 -0.3048)
			(stroke
				(width 0.1)
				(type default)
			)
			(layer "B.Fab")
		)
		(fp_line
			(start -0.12065 -0.3048)
			(end -0.67945 -0.3048)
			(stroke
				(width 0.1)
				(type default)
			)
			(layer "B.Fab")
		)
		(fp_line
			(start -0.67945 0.3048)
			(end -0.120396 0.3048)
			(stroke
				(width 0.1)
				(type default)
			)
			(layer "B.Fab")
		)
		(fp_line
			(start -0.67945 -0.3048)
			(end -0.67945 0.3048)
			(stroke
				(width 0.1)
				(type default)
			)
			(layer "B.Fab")
		)
		(pad "1" smd circle
			(at 0.40005 0)
			(size 0 0)
			(layers "B.Cu" "B.Mask" "B.Paste")
			(net "P0V8_PEX2")
		)
		(pad "2" smd circle
			(at -0.40005 0)
			(size 0 0)
			(layers "B.Cu" "B.Mask" "B.Paste")
			(net "SH_P0V8_PEX2_VSEN2_L")
		)
	)
	(footprint ""
		(layer "B.Cu")
		(at 164.965888 -138.421618 180)
		(property "Reference" "R105"
			(at 0 0 0)
			(layer "B.SilkS")
			(hide yes)
			(effects
				(font
					(size 1.27 1.27)
				)
				(justify mirror)
			)
		)
		(property "Value" ""
			(at 0 0 0)
			(layer "B.Fab")
			(effects
				(font
					(size 1.27 1.27)
				)
				(justify mirror)
			)
		)
		(duplicate_pad_numbers_are_jumpers no)
		(fp_line
			(start 0.7874 0.4064)
			(end 0.7874 -0.4064)
			(stroke
				(width 0.1524)
				(type default)
			)
			(layer "B.SilkS")
		)
		(fp_line
			(start 0.7874 -0.4064)
			(end -0.7874 -0.4064)
			(stroke
				(width 0.1524)
				(type default)
			)
			(layer "B.SilkS")
		)
		(fp_line
			(start -0.7874 0.4064)
			(end 0.7874 0.4064)
			(stroke
				(width 0.1524)
				(type default)
			)
			(layer "B.SilkS")
		)
		(fp_line
			(start -0.7874 -0.4064)
			(end -0.7874 0.4064)
			(stroke
				(width 0.1524)
				(type default)
			)
			(layer "B.SilkS")
		)
		(fp_line
			(start 0.67945 0.3048)
			(end 0.67945 -0.305054)
			(stroke
				(width 0.1)
				(type default)
			)
			(layer "B.Fab")
		)
		(fp_line
			(start 0.67945 -0.305054)
			(end 0.12065 -0.305054)
			(stroke
				(width 0.1)
				(type default)
			)
			(layer "B.Fab")
		)
		(fp_line
			(start 0.12065 0.3048)
			(end 0.67945 0.3048)
			(stroke
				(width 0.1)
				(type default)
			)
			(layer "B.Fab")
		)
		(fp_line
			(start 0.12065 0.2794)
			(end 0.12065 0.3048)
			(stroke
				(width 0.1)
				(type default)
			)
			(layer "B.Fab")
		)
		(fp_line
			(start 0.12065 -0.2794)
			(end -0.12065 -0.2794)
			(stroke
				(width 0.1)
				(type default)
			)
			(layer "B.Fab")
		)
		(fp_line
			(start 0.12065 -0.305054)
			(end 0.12065 -0.2794)
			(stroke
				(width 0.1)
				(type default)
			)
			(layer "B.Fab")
		)
		(fp_line
			(start -0.120396 0.3048)
			(end -0.120396 0.2794)
			(stroke
				(width 0.1)
				(type default)
			)
			(layer "B.Fab")
		)
		(fp_line
			(start -0.120396 0.2794)
			(end 0.12065 0.2794)
			(stroke
				(width 0.1)
				(type default)
			)
			(layer "B.Fab")
		)
		(fp_line
			(start -0.12065 -0.2794)
			(end -0.12065 -0.3048)
			(stroke
				(width 0.1)
				(type default)
			)
			(layer "B.Fab")
		)
		(fp_line
			(start -0.12065 -0.3048)
			(end -0.67945 -0.3048)
			(stroke
				(width 0.1)
				(type default)
			)
			(layer "B.Fab")
		)
		(fp_line
			(start -0.67945 0.3048)
			(end -0.120396 0.3048)
			(stroke
				(width 0.1)
				(type default)
			)
			(layer "B.Fab")
		)
		(fp_line
			(start -0.67945 -0.3048)
			(end -0.67945 0.3048)
			(stroke
				(width 0.1)
				(type default)
			)
			(layer "B.Fab")
		)
		(pad "1" smd circle
			(at 0.40005 0)
			(size 0 0)
			(layers "B.Cu" "B.Mask" "B.Paste")
			(net "NIC2_AUX_PWR_EN_R")
		)
		(pad "2" smd circle
			(at -0.40005 0)
			(size 0 0)
			(layers "B.Cu" "B.Mask" "B.Paste")
			(net "NIC2_AUX_PWR_EN")
		)
	)
	(footprint ""
		(layer "B.Cu")
		(at 56.007 -138.557 90)
		(property "Reference" "C856"
			(at 0 0 90)
			(layer "B.SilkS")
			(hide yes)
			(effects
				(font
					(size 1.27 1.27)
				)
				(justify mirror)
			)
		)
		(property "Value" ""
			(at 0 0 90)
			(layer "B.Fab")
			(effects
				(font
					(size 1.27 1.27)
				)
				(justify mirror)
			)
		)
		(duplicate_pad_numbers_are_jumpers no)
		(fp_line
			(start 0.7874 -0.4064)
			(end -0.7874 -0.4064)
			(stroke
				(width 0.1524)
				(type default)
			)
			(layer "B.SilkS")
		)
		(fp_line
			(start -0.7874 -0.4064)
			(end -0.7874 0.4064)
			(stroke
				(width 0.1524)
				(type default)
			)
			(layer "B.SilkS")
		)
		(fp_line
			(start 0.7874 0.4064)
			(end 0.7874 -0.4064)
			(stroke
				(width 0.1524)
				(type default)
			)
			(layer "B.SilkS")
		)
		(fp_line
			(start -0.7874 0.4064)
			(end 0.7874 0.4064)
			(stroke
				(width 0.1524)
				(type default)
			)
			(layer "B.SilkS")
		)
		(fp_line
			(start 0.67945 -0.305054)
			(end 0.12065 -0.305054)
			(stroke
				(width 0.1)
				(type default)
			)
			(layer "B.Fab")
		)
		(fp_line
			(start 0.12065 -0.305054)
			(end 0.12065 -0.2794)
			(stroke
				(width 0.1)
				(type default)
			)
			(layer "B.Fab")
		)
		(fp_line
			(start -0.12065 -0.3048)
			(end -0.67945 -0.3048)
			(stroke
				(width 0.1)
				(type default)
			)
			(layer "B.Fab")
		)
		(fp_line
			(start -0.67945 -0.3048)
			(end -0.67945 0.3048)
			(stroke
				(width 0.1)
				(type default)
			)
			(layer "B.Fab")
		)
		(fp_line
			(start 0.12065 -0.2794)
			(end -0.12065 -0.2794)
			(stroke
				(width 0.1)
				(type default)
			)
			(layer "B.Fab")
		)
		(fp_line
			(start -0.12065 -0.2794)
			(end -0.12065 -0.3048)
			(stroke
				(width 0.1)
				(type default)
			)
			(layer "B.Fab")
		)
		(fp_line
			(start 0.12065 0.2794)
			(end 0.12065 0.3048)
			(stroke
				(width 0.1)
				(type default)
			)
			(layer "B.Fab")
		)
		(fp_line
			(start -0.120396 0.2794)
			(end 0.12065 0.2794)
			(stroke
				(width 0.1)
				(type default)
			)
			(layer "B.Fab")
		)
		(fp_line
			(start 0.67945 0.3048)
			(end 0.67945 -0.305054)
			(stroke
				(width 0.1)
				(type default)
			)
			(layer "B.Fab")
		)
		(fp_line
			(start 0.12065 0.3048)
			(end 0.67945 0.3048)
			(stroke
				(width 0.1)
				(type default)
			)
			(layer "B.Fab")
		)
		(fp_line
			(start -0.120396 0.3048)
			(end -0.120396 0.2794)
			(stroke
				(width 0.1)
				(type default)
			)
			(layer "B.Fab")
		)
		(fp_line
			(start -0.67945 0.3048)
			(end -0.120396 0.3048)
			(stroke
				(width 0.1)
				(type default)
			)
			(layer "B.Fab")
		)
		(pad "1" smd circle
			(at 0.40005 0 270)
			(size 0 0)
			(layers "B.Cu" "B.Mask" "B.Paste")
			(net "P3V3_AUX")
		)
		(pad "2" smd circle
			(at -0.40005 0 270)
			(size 0 0)
			(layers "B.Cu" "B.Mask" "B.Paste")
			(net "GND")
		)
	)
	(footprint ""
		(layer "B.Cu")
		(at 171.474892 -293.99992 -90)
		(property "Reference" "C1377"
			(at 0 0 90)
			(layer "B.SilkS")
			(hide yes)
			(effects
				(font
					(size 1.27 1.27)
				)
				(justify mirror)
			)
		)
		(property "Value" ""
			(at 0 0 90)
			(layer "B.Fab")
			(effects
				(font
					(size 1.27 1.27)
				)
				(justify mirror)
			)
		)
		(duplicate_pad_numbers_are_jumpers no)
		(fp_line
			(start -0.299974 0.150114)
			(end 0.299974 0.150114)
			(stroke
				(width 0.1)
				(type default)
			)
			(layer "B.Fab")
		)
		(fp_line
			(start 0.299974 0.150114)
			(end 0.299974 -0.150114)
			(stroke
				(width 0.1)
				(type default)
			)
			(layer "B.Fab")
		)
		(fp_line
			(start -0.299974 -0.150114)
			(end -0.299974 0.150114)
			(stroke
				(width 0.1)
				(type default)
			)
			(layer "B.Fab")
		)
		(fp_line
			(start 0.299974 -0.150114)
			(end -0.299974 -0.150114)
			(stroke
				(width 0.1)
				(type default)
			)
			(layer "B.Fab")
		)
		(pad "1" smd rect
			(at 0.2667 0 90)
			(size 0.3048 0.381)
			(layers "B.Cu" "B.Mask" "B.Paste")
			(net "P0V8_PEX1")
		)
		(pad "2" smd rect
			(at -0.2667 0 90)
			(size 0.3048 0.381)
			(layers "B.Cu" "B.Mask" "B.Paste")
			(net "GND")
		)
	)
	(footprint ""
		(layer "B.Cu")
		(at 49.1998 -299.2755 180)
		(property "Reference" "C1132"
			(at 0 0 0)
			(layer "B.SilkS")
			(hide yes)
			(effects
				(font
					(size 1.27 1.27)
				)
				(justify mirror)
			)
		)
		(property "Value" ""
			(at 0 0 0)
			(layer "B.Fab")
			(effects
				(font
					(size 1.27 1.27)
				)
				(justify mirror)
			)
		)
		(duplicate_pad_numbers_are_jumpers no)
		(fp_line
			(start 0.299974 0.150114)
			(end 0.299974 -0.150114)
			(stroke
				(width 0.1)
				(type default)
			)
			(layer "B.Fab")
		)
		(fp_line
			(start 0.299974 -0.150114)
			(end -0.299974 -0.150114)
			(stroke
				(width 0.1)
				(type default)
			)
			(layer "B.Fab")
		)
		(fp_line
			(start -0.299974 0.150114)
			(end 0.299974 0.150114)
			(stroke
				(width 0.1)
				(type default)
			)
			(layer "B.Fab")
		)
		(fp_line
			(start -0.299974 -0.150114)
			(end -0.299974 0.150114)
			(stroke
				(width 0.1)
				(type default)
			)
			(layer "B.Fab")
		)
		(pad "1" smd rect
			(at 0.2667 0)
			(size 0.3048 0.381)
			(layers "B.Cu" "B.Mask" "B.Paste")
			(net "P0V8_PEX0")
		)
		(pad "2" smd rect
			(at -0.2667 0)
			(size 0.3048 0.381)
			(layers "B.Cu" "B.Mask" "B.Paste")
			(net "GND")
		)
	)
	(footprint ""
		(layer "B.Cu")
		(at 69.149976 -303.024794)
		(property "Reference" "C2993"
			(at 0 0 0)
			(layer "B.SilkS")
			(hide yes)
			(effects
				(font
					(size 1.27 1.27)
				)
				(justify mirror)
			)
		)
		(property "Value" ""
			(at 0 0 0)
			(layer "B.Fab")
			(effects
				(font
					(size 1.27 1.27)
				)
				(justify mirror)
			)
		)
		(duplicate_pad_numbers_are_jumpers no)
		(fp_line
			(start -0.299974 -0.150114)
			(end -0.299974 0.150114)
			(stroke
				(width 0.1)
				(type default)
			)
			(layer "B.Fab")
		)
		(fp_line
			(start -0.299974 0.150114)
			(end 0.299974 0.150114)
			(stroke
				(width 0.1)
				(type default)
			)
			(layer "B.Fab")
		)
		(fp_line
			(start 0.299974 -0.150114)
			(end -0.299974 -0.150114)
			(stroke
				(width 0.1)
				(type default)
			)
			(layer "B.Fab")
		)
		(fp_line
			(start 0.299974 0.150114)
			(end 0.299974 -0.150114)
			(stroke
				(width 0.1)
				(type default)
			)
			(layer "B.Fab")
		)
		(pad "1" smd rect
			(at 0.2667 0 180)
			(size 0.3048 0.381)
			(layers "B.Cu" "B.Mask" "B.Paste")
			(net "P1V8_PEX")
		)
		(pad "2" smd rect
			(at -0.2667 0 180)
			(size 0.3048 0.381)
			(layers "B.Cu" "B.Mask" "B.Paste")
			(net "GND")
		)
	)
	(footprint ""
		(layer "B.Cu")
		(at 161.964116 -146.148552 180)
		(property "Reference" "C879"
			(at 0 0 0)
			(layer "B.SilkS")
			(hide yes)
			(effects
				(font
					(size 1.27 1.27)
				)
				(justify mirror)
			)
		)
		(property "Value" ""
			(at 0 0 0)
			(layer "B.Fab")
			(effects
				(font
					(size 1.27 1.27)
				)
				(justify mirror)
			)
		)
		(duplicate_pad_numbers_are_jumpers no)
		(fp_line
			(start 0.299974 0.150114)
			(end 0.299974 -0.150114)
			(stroke
				(width 0.1)
				(type default)
			)
			(layer "B.Fab")
		)
		(fp_line
			(start 0.299974 -0.150114)
			(end -0.299974 -0.150114)
			(stroke
				(width 0.1)
				(type default)
			)
			(layer "B.Fab")
		)
		(fp_line
			(start -0.299974 0.150114)
			(end 0.299974 0.150114)
			(stroke
				(width 0.1)
				(type default)
			)
			(layer "B.Fab")
		)
		(fp_line
			(start -0.299974 -0.150114)
			(end -0.299974 0.150114)
			(stroke
				(width 0.1)
				(type default)
			)
			(layer "B.Fab")
		)
		(pad "1" smd rect
			(at 0.2667 0)
			(size 0.3048 0.381)
			(layers "B.Cu" "B.Mask" "B.Paste")
			(net "P12V_NIC2")
		)
		(pad "2" smd rect
			(at -0.2667 0)
			(size 0.3048 0.381)
			(layers "B.Cu" "B.Mask" "B.Paste")
			(net "GND")
		)
	)
	(footprint ""
		(layer "B.Cu")
		(at 340.27999 -282.167076 90)
		(property "Reference" "R6766"
			(at 0 0 90)
			(layer "B.SilkS")
			(hide yes)
			(effects
				(font
					(size 1.27 1.27)
				)
				(justify mirror)
			)
		)
		(property "Value" ""
			(at 0 0 90)
			(layer "B.Fab")
			(effects
				(font
					(size 1.27 1.27)
				)
				(justify mirror)
			)
		)
		(duplicate_pad_numbers_are_jumpers no)
		(fp_line
			(start 0.7874 -0.4064)
			(end -0.7874 -0.4064)
			(stroke
				(width 0.1524)
				(type default)
			)
			(layer "B.SilkS")
		)
		(fp_line
			(start -0.7874 -0.4064)
			(end -0.7874 0.4064)
			(stroke
				(width 0.1524)
				(type default)
			)
			(layer "B.SilkS")
		)
		(fp_line
			(start 0.7874 0.4064)
			(end 0.7874 -0.4064)
			(stroke
				(width 0.1524)
				(type default)
			)
			(layer "B.SilkS")
		)
		(fp_line
			(start -0.7874 0.4064)
			(end 0.7874 0.4064)
			(stroke
				(width 0.1524)
				(type default)
			)
			(layer "B.SilkS")
		)
		(fp_line
			(start 0.67945 -0.305054)
			(end 0.12065 -0.305054)
			(stroke
				(width 0.1)
				(type default)
			)
			(layer "B.Fab")
		)
		(fp_line
			(start 0.12065 -0.305054)
			(end 0.12065 -0.2794)
			(stroke
				(width 0.1)
				(type default)
			)
			(layer "B.Fab")
		)
		(fp_line
			(start -0.12065 -0.3048)
			(end -0.67945 -0.3048)
			(stroke
				(width 0.1)
				(type default)
			)
			(layer "B.Fab")
		)
		(fp_line
			(start -0.67945 -0.3048)
			(end -0.67945 0.3048)
			(stroke
				(width 0.1)
				(type default)
			)
			(layer "B.Fab")
		)
		(fp_line
			(start 0.12065 -0.2794)
			(end -0.12065 -0.2794)
			(stroke
				(width 0.1)
				(type default)
			)
			(layer "B.Fab")
		)
		(fp_line
			(start -0.12065 -0.2794)
			(end -0.12065 -0.3048)
			(stroke
				(width 0.1)
				(type default)
			)
			(layer "B.Fab")
		)
		(fp_line
			(start 0.12065 0.2794)
			(end 0.12065 0.3048)
			(stroke
				(width 0.1)
				(type default)
			)
			(layer "B.Fab")
		)
		(fp_line
			(start -0.120396 0.2794)
			(end 0.12065 0.2794)
			(stroke
				(width 0.1)
				(type default)
			)
			(layer "B.Fab")
		)
		(fp_line
			(start 0.67945 0.3048)
			(end 0.67945 -0.305054)
			(stroke
				(width 0.1)
				(type default)
			)
			(layer "B.Fab")
		)
		(fp_line
			(start 0.12065 0.3048)
			(end 0.67945 0.3048)
			(stroke
				(width 0.1)
				(type default)
			)
			(layer "B.Fab")
		)
		(fp_line
			(start -0.120396 0.3048)
			(end -0.120396 0.2794)
			(stroke
				(width 0.1)
				(type default)
			)
			(layer "B.Fab")
		)
		(fp_line
			(start -0.67945 0.3048)
			(end -0.120396 0.3048)
			(stroke
				(width 0.1)
				(type default)
			)
			(layer "B.Fab")
		)
		(pad "1" smd circle
			(at 0.40005 0 270)
			(size 0 0)
			(layers "B.Cu" "B.Mask" "B.Paste")
			(net "P0V8_PEX2_VCC1")
		)
		(pad "2" smd circle
			(at -0.40005 0 270)
			(size 0 0)
			(layers "B.Cu" "B.Mask" "B.Paste")
			(net "P0V8_PEX2_EN1")
		)
	)
	(footprint ""
		(layer "B.Cu")
		(at 169.099992 -303.499774 -90)
		(property "Reference" "C3087"
			(at 0 0 90)
			(layer "B.SilkS")
			(hide yes)
			(effects
				(font
					(size 1.27 1.27)
				)
				(justify mirror)
			)
		)
		(property "Value" ""
			(at 0 0 90)
			(layer "B.Fab")
			(effects
				(font
					(size 1.27 1.27)
				)
				(justify mirror)
			)
		)
		(duplicate_pad_numbers_are_jumpers no)
		(fp_line
			(start -0.299974 0.150114)
			(end 0.299974 0.150114)
			(stroke
				(width 0.1)
				(type default)
			)
			(layer "B.Fab")
		)
		(fp_line
			(start 0.299974 0.150114)
			(end 0.299974 -0.150114)
			(stroke
				(width 0.1)
				(type default)
			)
			(layer "B.Fab")
		)
		(fp_line
			(start -0.299974 -0.150114)
			(end -0.299974 0.150114)
			(stroke
				(width 0.1)
				(type default)
			)
			(layer "B.Fab")
		)
		(fp_line
			(start 0.299974 -0.150114)
			(end -0.299974 -0.150114)
			(stroke
				(width 0.1)
				(type default)
			)
			(layer "B.Fab")
		)
		(pad "1" smd rect
			(at 0.2667 0 90)
			(size 0.3048 0.381)
			(layers "B.Cu" "B.Mask" "B.Paste")
			(net "P1V25_PEX1")
		)
		(pad "2" smd rect
			(at -0.2667 0 90)
			(size 0.3048 0.381)
			(layers "B.Cu" "B.Mask" "B.Paste")
			(net "GND")
		)
	)
)
